# TIMECARD (Time Appliance Project (Time Card)) — schematic netlist excerpt (pin names and nets, part order shuffled) for the footprints in the layout excerpt that follows; sources: Cadence DE-HDL packaged netlist, KiCad conversion of R4006-B0001-02_R01.brd

R445  RESISTOR  5.1KOHM 1%  pkg SMC_0402R_H016  page 24 : \1\ = UNNAMED_524_CONNUSB14PGH4FRAT_1 ; \2\ = SG
R172  RESISTOR  10KOHM 1%  pkg SMC_0402R_H016  page 25 : \1\ = XP3R3V_FPGA ; \2\ = FPGA_IO_1

(kicad_pcb
	(version 20260206)
	(generator "pcbnew")
	(generator_version "10.0")
	(general
		(thickness 1.6)
		(legacy_teardrops no)
	)
	(paper "A4")
	(title_block
		(title "timecard-production-celestica-r4006 — R4006-B0001-02_R01.brd")
		(comment 1 "Time Appliance Project (Time Card) / footprints 280-281 of 1113")
	)
	(layers
		(0 "F.Cu" signal "TOP")
		(4 "In1.Cu" signal "L02_GND1")
		(6 "In2.Cu" signal "L03_SIG1")
		(8 "In3.Cu" signal "L04_GND2")
		(10 "In4.Cu" signal "L05_VCC1")
		(12 "In5.Cu" signal "L06_VCC2")
		(14 "In6.Cu" signal "L07_GND3")
		(16 "In7.Cu" signal "L08_SIG2")
		(18 "In8.Cu" signal "L09_GND4")
		(2 "B.Cu" signal "BOTTOM")
		(9 "F.Adhes" user "F.Adhesive")
		(11 "B.Adhes" user "B.Adhesive")
		(13 "F.Paste" user "Package Geometry/Pastemask Top")
		(15 "B.Paste" user "Package Geometry/Pastemask Bottom")
		(5 "F.SilkS" user "Ref Des/Silkscreen Top")
		(7 "B.SilkS" user "Ref Des/Silkscreen Bottom")
		(1 "F.Mask" user "Board Geometry/Soldermask Top")
		(3 "B.Mask" user "Board Geometry/Soldermask Bottom")
		(17 "Dwgs.User" user "User.Drawings")
		(19 "Cmts.User" user "User.Comments")
		(21 "Eco1.User" user "User.Eco1")
		(23 "Eco2.User" user "User.Eco2")
		(25 "Edge.Cuts" user "Board Geometry/Outline")
		(27 "Margin" user)
		(31 "F.CrtYd" user "Package Geometry/Place Bound Top")
		(29 "B.CrtYd" user "Package Geometry/Place Bound Bottom")
		(35 "F.Fab" user "Ref Des/Assembly Top")
		(33 "B.Fab" user "Ref Des/Assembly Bottom")
	)
	(footprint ""
		(layer "F.Cu")
		(at 99.5426 -64.2874 -90)
		(property "Reference" "R172"
			(at 2.6924 -0.69977 90)
			(unlocked yes)
			(layer "F.SilkS")
			(effects
				(font
					(size 0.7874 0.5842)
					(thickness 0.1524)
				)
			)
		)
		(property "Value" "VAL*"
			(at 0.02032 2.13233 270)
			(unlocked yes)
			(layer "F.Fab")
			(hide yes)
			(effects
				(font
					(size 0.7874 0.5842)
					(thickness 0.1524)
				)
			)
		)
		(property "Tolerance" "TOL*"
			(at 0.044704 3.05435 270)
			(unlocked yes)
			(layer "Cmts.User")
			(hide yes)
			(effects
				(font
					(size 0.7874 0.5842)
					(thickness 0.1524)
				)
			)
		)
		(property "User Part Number" "PARTNUM*"
			(at 0.02032 4.024884 270)
			(unlocked yes)
			(layer "Cmts.User")
			(hide yes)
			(effects
				(font
					(size 0.7874 0.5842)
					(thickness 0.1524)
				)
			)
		)
		(property "Device Type" "RESISTOR-G155-11002-01,10KOHM,A"
			(at 0.008382 1.210564 270)
			(unlocked yes)
			(layer "F.Fab")
			(hide yes)
			(effects
				(font
					(size 0.7874 0.5842)
					(thickness 0.1524)
				)
			)
		)
		(duplicate_pad_numbers_are_jumpers no)
		(fp_line
			(start -1.143 0.5588)
			(end 1.143 0.5588)
			(stroke
				(width 0.1)
				(type default)
			)
			(layer "F.SilkS")
		)
		(fp_line
			(start 1.143 0.5588)
			(end 1.143 -0.5588)
			(stroke
				(width 0.1)
				(type default)
			)
			(layer "F.SilkS")
		)
		(fp_line
			(start -1.143 -0.5588)
			(end -1.143 0.5588)
			(stroke
				(width 0.1)
				(type default)
			)
			(layer "F.SilkS")
		)
		(fp_line
			(start 1.143 -0.5588)
			(end -1.143 -0.5588)
			(stroke
				(width 0.1)
				(type default)
			)
			(layer "F.SilkS")
		)
		(fp_rect
			(start 1.143 0.5588)
			(end -1.143 -0.5588)
			(stroke
				(width 0)
				(type default)
			)
			(fill no)
			(layer "F.CrtYd")
		)
		(fp_line
			(start -0.508 0.3048)
			(end 0.508 0.3048)
			(stroke
				(width 0.1)
				(type default)
			)
			(layer "F.Fab")
		)
		(fp_line
			(start 0.508 0.3048)
			(end 0.508 -0.3048)
			(stroke
				(width 0.1)
				(type default)
			)
			(layer "F.Fab")
		)
		(fp_line
			(start -0.508 -0.3048)
			(end -0.508 0.3048)
			(stroke
				(width 0.1)
				(type default)
			)
			(layer "F.Fab")
		)
		(fp_line
			(start 0.508 -0.3048)
			(end -0.508 -0.3048)
			(stroke
				(width 0.1)
				(type default)
			)
			(layer "F.Fab")
		)
		(pad "1" smd rect
			(at -0.5334 0 270)
			(size 0.7112 0.6096)
			(layers "F.Cu" "F.Mask" "F.Paste")
			(net "XP3R3V_FPGA")
		)
		(pad "2" smd rect
			(at 0.5334 0 270)
			(size 0.7112 0.6096)
			(layers "F.Cu" "F.Mask" "F.Paste")
			(net "FPGA_IO_1")
		)
		(zone
			(layer "F.Cu")
			(hatch none 0.5)
			(connect_pads
				(clearance 0)
			)
			(min_thickness 0.25)
			(keepout
				(tracks allowed)
				(vias not_allowed)
				(pads allowed)
				(copperpour not_allowed)
				(footprints allowed)
			)
			(placement
				(enabled no)
				(sheetname "")
			)
			(fill
				(thermal_gap 0.5)
				(thermal_bridge_width 0.5)
				(island_removal_mode 0)
			)
			(polygon
				(pts
					(xy 99.2378 -64.2112) (xy 99.8474 -64.2112) (xy 99.8474 -64.3636) (xy 99.2378 -64.3636)
				)
			)
		)
	)
	(footprint ""
		(layer "F.Cu")
		(at 15.494 -83.566)
		(property "Reference" "R445"
			(at -1.397 1.18237 0)
			(unlocked yes)
			(layer "F.SilkS")
			(effects
				(font
					(size 0.7874 0.5842)
					(thickness 0.1524)
				)
			)
		)
		(property "Value" "VAL*"
			(at 0.02032 2.13233 0)
			(unlocked yes)
			(layer "F.Fab")
			(hide yes)
			(effects
				(font
					(size 0.7874 0.5842)
					(thickness 0.1524)
				)
			)
		)
		(property "Tolerance" "TOL*"
			(at 0.044704 3.05435 0)
			(unlocked yes)
			(layer "Cmts.User")
			(hide yes)
			(effects
				(font
					(size 0.7874 0.5842)
					(thickness 0.1524)
				)
			)
		)
		(property "User Part Number" "PARTNUM*"
			(at 0.02032 4.024884 0)
			(unlocked yes)
			(layer "Cmts.User")
			(hide yes)
			(effects
				(font
					(size 0.7874 0.5842)
					(thickness 0.1524)
				)
			)
		)
		(property "Device Type" "RESISTOR-G155-05101-01,5.1KOHMA"
			(at 0.008382 1.210564 0)
			(unlocked yes)
			(layer "F.Fab")
			(hide yes)
			(effects
				(font
					(size 0.7874 0.5842)
					(thickness 0.1524)
				)
			)
		)
		(duplicate_pad_numbers_are_jumpers no)
		(fp_line
			(start -1.143 -0.5588)
			(end -1.143 0.5588)
			(stroke
				(width 0.1)
				(type default)
			)
			(layer "F.SilkS")
		)
		(fp_line
			(start -1.143 0.5588)
			(end 1.143 0.5588)
			(stroke
				(width 0.1)
				(type default)
			)
			(layer "F.SilkS")
		)
		(fp_line
			(start 1.143 -0.5588)
			(end -1.143 -0.5588)
			(stroke
				(width 0.1)
				(type default)
			)
			(layer "F.SilkS")
		)
		(fp_line
			(start 1.143 0.5588)
			(end 1.143 -0.5588)
			(stroke
				(width 0.1)
				(type default)
			)
			(layer "F.SilkS")
		)
		(fp_poly
			(pts
				(xy -1.143 0.5588) (xy 1.143 0.5588) (xy 1.143 -0.5588) (xy -1.143 -0.5588)
			)
			(stroke
				(width 0)
				(type default)
			)
			(fill no)
			(layer "F.CrtYd")
		)
		(fp_line
			(start -0.508 -0.3048)
			(end -0.508 0.3048)
			(stroke
				(width 0.1)
				(type default)
			)
			(layer "F.Fab")
		)
		(fp_line
			(start -0.508 0.3048)
			(end 0.508 0.3048)
			(stroke
				(width 0.1)
				(type default)
			)
			(layer "F.Fab")
		)
		(fp_line
			(start 0.508 -0.3048)
			(end -0.508 -0.3048)
			(stroke
				(width 0.1)
				(type default)
			)
			(layer "F.Fab")
		)
		(fp_line
			(start 0.508 0.3048)
			(end 0.508 -0.3048)
			(stroke
				(width 0.1)
				(type default)
			)
			(layer "F.Fab")
		)
		(pad "1" smd rect
			(at -0.5334 0)
			(size 0.7112 0.6096)
			(layers "F.Cu" "F.Mask" "F.Paste")
			(net "UNNAMED_524_CONNUSB14PGH4FRAT_1")
		)
		(pad "2" smd rect
			(at 0.5334 0)
			(size 0.7112 0.6096)
			(layers "F.Cu" "F.Mask" "F.Paste")
			(net "SG")
		)
		(zone
			(layer "F.Cu")
			(hatch none 0.5)
			(connect_pads
				(clearance 0)
			)
			(min_thickness 0.25)
			(keepout
				(tracks not_allowed)
				(vias allowed)
				(pads allowed)
				(copperpour not_allowed)
				(footprints allowed)
			)
			(placement
				(enabled no)
				(sheetname "")
			)
			(fill
				(thermal_gap 0.5)
				(thermal_bridge_width 0.5)
				(island_removal_mode 0)
			)
			(polygon
				(pts
					(xy 15.4178 -83.2612) (xy 15.5702 -83.2612) (xy 15.5702 -83.8708) (xy 15.4178 -83.8708)
				)
			)
		)
		(zone
			(layer "F.Cu")
			(hatch none 0.5)
			(connect_pads
				(clearance 0)
			)
			(min_thickness 0.25)
			(keepout
				(tracks allowed)
				(vias not_allowed)
				(pads allowed)
				(copperpour not_allowed)
				(footprints allowed)
			)
			(placement
				(enabled no)
				(sheetname "")
			)
			(fill
				(thermal_gap 0.5)
				(thermal_bridge_width 0.5)
				(island_removal_mode 0)
			)
			(polygon
				(pts
					(xy 15.4178 -83.2612) (xy 15.5702 -83.2612) (xy 15.5702 -83.8708) (xy 15.4178 -83.8708)
				)
			)
		)
	)
)
